(kicad_pcb
	(version 20260206)
	(generator "pcbnew")
	(generator_version "10.0")
	(general
		(thickness 1.21888)
		(legacy_teardrops no)
	)
	(paper "A4")
	(title_block
		(title "timecard-v8 — TimeCard-DC-V8_EXP.PcbDoc")
		(comment 1 "Time Appliance Project (Time Card) / footprints 201-208 of 288")
	)
	(layers
		(0 "F.Cu" signal "TOP")
		(4 "In1.Cu" signal "SGND")
		(6 "In2.Cu" signal "IN1")
		(8 "In3.Cu" signal "IN2")
		(10 "In4.Cu" signal "SGND1")
		(2 "B.Cu" signal "BOTTOM")
		(9 "F.Adhes" user "F.Adhesive")
		(11 "B.Adhes" user "B.Adhesive")
		(13 "F.Paste" user "Top Paste")
		(15 "B.Paste" user "Bottom Paste")
		(5 "F.SilkS" user "Top Overlay")
		(7 "B.SilkS" user "Bottom Overlay")
		(1 "F.Mask" user "Top Solder")
		(3 "B.Mask" user "Bottom Solder")
		(17 "Dwgs.User" user "User.Drawings")
		(19 "Cmts.User" user "User.Comments")
		(21 "Eco1.User" user "User.Eco1")
		(23 "Eco2.User" user "User.Eco2")
		(25 "Edge.Cuts" user)
		(27 "Margin" user)
		(31 "F.CrtYd" user "Top Courtyard")
		(29 "B.CrtYd" user "Bottom Courtyard")
		(35 "F.Fab" user "Top Component Center")
		(33 "B.Fab" user "Bottom Component Center")
	)
	(footprint "Vault:FP-D0008A-MFG"
		(layer "F.Cu")
		(at 231.1261 131.3162 180)
		(property "Reference" "U19"
			(at -0.2286 3.373079 0)
			(unlocked yes)
			(layer "F.SilkS")
			(effects
				(font
					(size 0.762 0.762)
					(thickness 0.2286)
				)
			)
		)
		(property "Value" "INA219BIDR"
			(at 3.16005 4.408671 180)
			(unlocked yes)
			(layer "F.SilkS")
			(hide yes)
			(effects
				(font
					(size 0.762 0.762)
					(thickness 0.2286)
				)
			)
		)
		(sheetname "POWER")
		(sheetfile "POWER.kicad_sch")
		(duplicate_pad_numbers_are_jumpers no)
		(fp_line
			(start 1.5 2.5)
			(end -1.5 2.5)
			(stroke
				(width 0.2)
				(type solid)
			)
			(layer "F.SilkS")
		)
		(fp_line
			(start 1.5 -2.5)
			(end 1.5 2.5)
			(stroke
				(width 0.2)
				(type solid)
			)
			(layer "F.SilkS")
		)
		(fp_line
			(start 1.5 -2.5)
			(end -1.5 -2.5)
			(stroke
				(width 0.2)
				(type solid)
			)
			(layer "F.SilkS")
		)
		(fp_line
			(start -1.5 -2.5)
			(end -1.5 2.5)
			(stroke
				(width 0.2)
				(type solid)
			)
			(layer "F.SilkS")
		)
		(fp_circle
			(center -0.725 -1.725)
			(end -0.725 -1.475)
			(stroke
				(width 0.5)
				(type solid)
			)
			(fill no)
			(layer "F.SilkS")
		)
		(fp_circle
			(center -4.05 -1.905)
			(end -4.05 -1.78)
			(stroke
				(width 0.25)
				(type solid)
			)
			(fill no)
			(layer "F.SilkS")
		)
		(fp_line
			(start 3.575 2.75)
			(end -3.575 2.75)
			(stroke
				(width 0.2)
				(type solid)
			)
			(layer "F.CrtYd")
		)
		(fp_line
			(start 3.575 -2.75)
			(end 3.575 2.75)
			(stroke
				(width 0.2)
				(type solid)
			)
			(layer "F.CrtYd")
		)
		(fp_line
			(start 3.575 -2.75)
			(end -3.575 -2.75)
			(stroke
				(width 0.2)
				(type solid)
			)
			(layer "F.CrtYd")
		)
		(fp_line
			(start -3.575 -2.75)
			(end -3.575 2.75)
			(stroke
				(width 0.2)
				(type solid)
			)
			(layer "F.CrtYd")
		)
		(fp_line
			(start 3.575 2.75)
			(end -3.575 2.75)
			(stroke
				(width 0.2)
				(type solid)
			)
			(layer "F.Fab")
		)
		(fp_line
			(start 3.575 -2.75)
			(end 3.575 2.75)
			(stroke
				(width 0.2)
				(type solid)
			)
			(layer "F.Fab")
		)
		(fp_line
			(start 3.575 -2.75)
			(end -3.575 -2.75)
			(stroke
				(width 0.2)
				(type solid)
			)
			(layer "F.Fab")
		)
		(fp_line
			(start 0.5 0)
			(end -0.49999 0)
			(stroke
				(width 0.1)
				(type solid)
			)
			(layer "F.Fab")
		)
		(fp_line
			(start 0 -0.5)
			(end 0 0.5)
			(stroke
				(width 0.1)
				(type solid)
			)
			(layer "F.Fab")
		)
		(fp_line
			(start -3.575 -2.75)
			(end -3.575 2.75)
			(stroke
				(width 0.2)
				(type solid)
			)
			(layer "F.Fab")
		)
		(fp_text user "${REFERENCE}"
			(at 0 0.09601 180)
			(unlocked yes)
			(layer "F.Fab")
			(effects
				(font
					(face "Arial")
					(size 0.63 0.63)
					(thickness 0.1)
				)
				(justify left bottom)
			)
		)
		(pad "1" smd roundrect
			(at -2.7 -1.905 180)
			(size 1.55 0.6)
			(layers "F.Cu" "F.Mask" "F.Paste")
			(roundrect_rratio 0.085)
			(net "NetR80_1")
			(solder_mask_margin 0)
			(solder_paste_margin 0)
		)
		(pad "2" smd roundrect
			(at -2.7 -0.635 180)
			(size 1.55 0.6)
			(layers "F.Cu" "F.Mask" "F.Paste")
			(roundrect_rratio 0.085)
			(net "NetR79_1")
			(solder_mask_margin 0)
			(solder_paste_margin 0)
		)
		(pad "3" smd roundrect
			(at -2.7 0.635 180)
			(size 1.55 0.6)
			(layers "F.Cu" "F.Mask" "F.Paste")
			(roundrect_rratio 0.085)
			(net "SDA")
			(solder_mask_margin 0)
			(solder_paste_margin 0)
		)
		(pad "4" smd roundrect
			(at -2.7 1.905 180)
			(size 1.55 0.6)
			(layers "F.Cu" "F.Mask" "F.Paste")
			(roundrect_rratio 0.085)
			(net "SCL")
			(solder_mask_margin 0)
			(solder_paste_margin 0)
		)
		(pad "5" smd roundrect
			(at 2.7 1.905 180)
			(size 1.55 0.6)
			(layers "F.Cu" "F.Mask" "F.Paste")
			(roundrect_rratio 0.085)
			(net "+3.3V")
			(solder_mask_margin 0)
			(solder_paste_margin 0)
		)
		(pad "6" smd roundrect
			(at 2.7 0.635 180)
			(size 1.55 0.6)
			(layers "F.Cu" "F.Mask" "F.Paste")
			(roundrect_rratio 0.085)
			(net "GND")
			(solder_mask_margin 0)
			(solder_paste_margin 0)
		)
		(pad "7" smd roundrect
			(at 2.7 -0.635 180)
			(size 1.55 0.6)
			(layers "F.Cu" "F.Mask" "F.Paste")
			(roundrect_rratio 0.085)
			(net "+3.3V")
			(solder_mask_margin 0)
			(solder_paste_margin 0)
		)
		(pad "8" smd roundrect
			(at 2.7 -1.905 180)
			(size 1.55 0.6)
			(layers "F.Cu" "F.Mask" "F.Paste")
			(roundrect_rratio 0.085)
			(net "P3V3_SENSE")
			(solder_mask_margin 0)
			(solder_paste_margin 0)
		)
	)
	(footprint "Vault:FP-C0603C105K3PACTU-MFG"
		(layer "F.Cu")
		(at 82.3761 86.9662 -90)
		(property "Reference" "C38"
			(at -0.3286 2.973069 90)
			(unlocked yes)
			(layer "F.SilkS")
			(effects
				(font
					(size 0.762 0.762)
					(thickness 0.2286)
				)
			)
		)
		(property "Value" "1uF"
			(at -2.859281 1.45988 180)
			(unlocked yes)
			(layer "F.SilkS")
			(hide yes)
			(effects
				(font
					(size 0.762 0.762)
					(thickness 0.2286)
				)
			)
		)
		(sheetname "USER_IO_STATUS")
		(sheetfile "USER_IO_STATUS.kicad_sch")
		(duplicate_pad_numbers_are_jumpers no)
		(fp_line
			(start 0.875 0.825)
			(end -0.875 0.825)
			(stroke
				(width 0.2)
				(type solid)
			)
			(layer "F.SilkS")
		)
		(fp_line
			(start 0.875 -0.825)
			(end -0.875 -0.825)
			(stroke
				(width 0.2)
				(type solid)
			)
			(layer "F.SilkS")
		)
		(fp_line
			(start -1.2 0.6)
			(end -1.2 -0.6)
			(stroke
				(width 0.2)
				(type solid)
			)
			(layer "F.CrtYd")
		)
		(fp_line
			(start 1.2 0.6)
			(end -1.2 0.6)
			(stroke
				(width 0.2)
				(type solid)
			)
			(layer "F.CrtYd")
		)
		(fp_line
			(start 1.2 0.6)
			(end 1.2 -0.6)
			(stroke
				(width 0.2)
				(type solid)
			)
			(layer "F.CrtYd")
		)
		(fp_line
			(start 1.2 -0.6)
			(end -1.2 -0.6)
			(stroke
				(width 0.2)
				(type solid)
			)
			(layer "F.CrtYd")
		)
		(fp_line
			(start -1.2 0.6)
			(end -1.2 -0.6)
			(stroke
				(width 0.2)
				(type solid)
			)
			(layer "F.Fab")
		)
		(fp_line
			(start 1.2 0.6)
			(end -1.2 0.6)
			(stroke
				(width 0.2)
				(type solid)
			)
			(layer "F.Fab")
		)
		(fp_line
			(start 1.2 0.6)
			(end 1.2 -0.6)
			(stroke
				(width 0.2)
				(type solid)
			)
			(layer "F.Fab")
		)
		(fp_line
			(start 0 0.5)
			(end 0 -0.5)
			(stroke
				(width 0.1)
				(type solid)
			)
			(layer "F.Fab")
		)
		(fp_line
			(start 0.5 0)
			(end -0.5 0)
			(stroke
				(width 0.1)
				(type solid)
			)
			(layer "F.Fab")
		)
		(fp_line
			(start 1.2 -0.6)
			(end -1.2 -0.6)
			(stroke
				(width 0.2)
				(type solid)
			)
			(layer "F.Fab")
		)
		(pad "1" smd rect
			(at -0.6 0 270)
			(size 0.75 0.9)
			(layers "F.Cu" "F.Mask" "F.Paste")
			(net "+3.3V")
			(solder_mask_margin 0)
			(solder_paste_margin 0)
		)
		(pad "2" smd rect
			(at 0.6 0 270)
			(size 0.75 0.9)
			(layers "F.Cu" "F.Mask" "F.Paste")
			(net "GND")
			(solder_mask_margin 0)
			(solder_paste_margin 0)
		)
	)
	(footprint "Passives:SOT65P210X110-3N"
		(layer "F.Cu")
		(at 195.08636 143.47763)
		(property "Reference" "D6"
			(at -3.16026 -1.068085 0)
			(unlocked yes)
			(layer "F.SilkS")
			(effects
				(font
					(size 0.762 0.762)
					(thickness 0.2286)
				)
				(justify left bottom)
			)
		)
		(property "Value" "BAT54SW"
			(at -4.0249 -1.823555 0)
			(unlocked yes)
			(layer "F.SilkS")
			(hide yes)
			(effects
				(font
					(size 0.762 0.762)
					(thickness 0.2286)
				)
				(justify left bottom)
			)
		)
		(sheetname "PCIe_JTAG")
		(sheetfile "PCIe_JTAG.kicad_sch")
		(duplicate_pad_numbers_are_jumpers no)
		(fp_line
			(start -0.325 -1.1)
			(end 0.675 -1.1)
			(stroke
				(width 0.2)
				(type solid)
			)
			(layer "F.SilkS")
		)
		(fp_line
			(start -0.325 1.1)
			(end 0.675 1.1)
			(stroke
				(width 0.2)
				(type solid)
			)
			(layer "F.SilkS")
		)
		(fp_line
			(start 0.675 -0.65)
			(end 0.675 -1.1)
			(stroke
				(width 0.2)
				(type solid)
			)
			(layer "F.SilkS")
		)
		(fp_line
			(start 0.675 1.1)
			(end 0.675 0.65)
			(stroke
				(width 0.2)
				(type solid)
			)
			(layer "F.SilkS")
		)
		(fp_circle
			(center -1.125 -1.45)
			(end -1.125 -1.575)
			(stroke
				(width 0.25)
				(type solid)
			)
			(fill no)
			(layer "F.SilkS")
		)
		(pad "1" smd rect
			(at -1.125 -0.65 90)
			(size 0.5 0.9)
			(layers "F.Cu" "F.Mask" "F.Paste")
			(net "GND")
		)
		(pad "2" smd rect
			(at -1.125 0.65 90)
			(size 0.5 0.9)
			(layers "F.Cu" "F.Mask" "F.Paste")
			(net "+3.3V")
		)
		(pad "3" smd rect
			(at 1.125 0 90)
			(size 0.5 0.9)
			(layers "F.Cu" "F.Mask" "F.Paste")
			(net "FPGA_TDO")
		)
	)
	(footprint "Vault:FP-RC0603-0_55-MFG"
		(layer "F.Cu")
		(at 83.4261 83.1162)
		(property "Reference" "R40"
			(at -0.2286 1.473069 180)
			(unlocked yes)
			(layer "F.SilkS")
			(effects
				(font
					(size 0.762 0.762)
					(thickness 0.2286)
				)
			)
		)
		(property "Value" "DNI_100k"
			(at -2.998991 2.37408 270)
			(unlocked yes)
			(layer "F.SilkS")
			(hide yes)
			(effects
				(font
					(size 0.762 0.762)
					(thickness 0.2286)
				)
			)
		)
		(sheetname "USER_IO_STATUS")
		(sheetfile "USER_IO_STATUS.kicad_sch")
		(duplicate_pad_numbers_are_jumpers no)
		(fp_line
			(start -0.025 -0.45)
			(end 0.025 -0.45)
			(stroke
				(width 0.2)
				(type solid)
			)
			(layer "F.SilkS")
		)
		(fp_line
			(start -0.025 0.45)
			(end 0.025 0.45)
			(stroke
				(width 0.2)
				(type solid)
			)
			(layer "F.SilkS")
		)
		(fp_line
			(start -1.4 -0.55)
			(end 1.4 -0.55)
			(stroke
				(width 0.2)
				(type solid)
			)
			(layer "F.CrtYd")
		)
		(fp_line
			(start -1.4 0.55)
			(end -1.4 -0.55)
			(stroke
				(width 0.2)
				(type solid)
			)
			(layer "F.CrtYd")
		)
		(fp_line
			(start -1.4 0.55)
			(end 1.4 0.55)
			(stroke
				(width 0.2)
				(type solid)
			)
			(layer "F.CrtYd")
		)
		(fp_line
			(start 1.4 0.55)
			(end 1.4 -0.55)
			(stroke
				(width 0.2)
				(type solid)
			)
			(layer "F.CrtYd")
		)
		(fp_line
			(start -1.4 -0.55)
			(end 1.4 -0.55)
			(stroke
				(width 0.2)
				(type solid)
			)
			(layer "F.Fab")
		)
		(fp_line
			(start -1.4 0.55)
			(end -1.4 -0.55)
			(stroke
				(width 0.2)
				(type solid)
			)
			(layer "F.Fab")
		)
		(fp_line
			(start -1.4 0.55)
			(end 1.4 0.55)
			(stroke
				(width 0.2)
				(type solid)
			)
			(layer "F.Fab")
		)
		(fp_line
			(start -0.5 0)
			(end 0.5 0)
			(stroke
				(width 0.1)
				(type solid)
			)
			(layer "F.Fab")
		)
		(fp_line
			(start 0 0.5)
			(end 0 -0.5)
			(stroke
				(width 0.1)
				(type solid)
			)
			(layer "F.Fab")
		)
		(fp_line
			(start 1.4 0.55)
			(end 1.4 -0.55)
			(stroke
				(width 0.2)
				(type solid)
			)
			(layer "F.Fab")
		)
		(pad "1" smd rect
			(at -0.85 0)
			(size 0.9 0.8)
			(layers "F.Cu" "F.Mask" "F.Paste")
			(net "GND")
			(solder_mask_margin 0)
			(solder_paste_margin 0)
		)
		(pad "2" smd rect
			(at 0.85 0)
			(size 0.9 0.8)
			(layers "F.Cu" "F.Mask" "F.Paste")
			(net "NetR40_2")
			(solder_mask_margin 0)
			(solder_paste_margin 0)
		)
	)
	(footprint "Resistors:RESC2012X50N"
		(layer "F.Cu")
		(at 229.5261 142.1162 -90)
		(property "Reference" "R20"
			(at -1.2 -1.506655 270)
			(unlocked yes)
			(layer "F.SilkS")
			(effects
				(font
					(size 0.762 0.762)
					(thickness 0.2286)
				)
				(justify left bottom)
			)
		)
		(property "Value" "CRCW080533R0FKEA"
			(at -8.029165 -4.5751 0)
			(unlocked yes)
			(layer "F.SilkS")
			(hide yes)
			(effects
				(font
					(size 0.762 0.762)
					(thickness 0.2286)
				)
				(justify left bottom)
			)
		)
		(sheetname "PCIe_JTAG")
		(sheetfile "PCIe_JTAG.kicad_sch")
		(duplicate_pad_numbers_are_jumpers no)
		(fp_line
			(start 0 0.762)
			(end 0 -0.762)
			(stroke
				(width 0.1524)
				(type solid)
			)
			(layer "F.SilkS")
		)
		(pad "1" smd rect
			(at -1 0)
			(size 1.45 0.95)
			(layers "F.Cu" "F.Mask" "F.Paste")
			(net "FPGA_TMS")
		)
		(pad "2" smd rect
			(at 1 0)
			(size 1.45 0.95)
			(layers "F.Cu" "F.Mask" "F.Paste")
			(net "NetR20_2")
		)
	)
	(footprint "Vault:RESC1005X40X25LL05T05"
		(layer "F.Cu")
		(at 186.3261 82.8162 180)
		(property "Reference" "R52"
			(at 1.1714 1.673079 0)
			(unlocked yes)
			(layer "F.SilkS")
			(effects
				(font
					(size 0.762 0.762)
					(thickness 0.2286)
				)
			)
		)
		(property "Value" "4.7K_0402"
			(at -3.024391 2.374045 90)
			(unlocked yes)
			(layer "F.SilkS")
			(hide yes)
			(effects
				(font
					(size 0.762 0.762)
					(thickness 0.2286)
				)
			)
		)
		(sheetname "GPS_IMU_SENSORS")
		(sheetfile "GPS_IMU_SENSORS.kicad_sch")
		(duplicate_pad_numbers_are_jumpers no)
		(pad "1" smd rect
			(at -0.4 0 270)
			(size 0.45 0.45)
			(layers "F.Cu" "F.Mask" "F.Paste")
			(net "NetR52_1")
		)
		(pad "2" smd rect
			(at 0.4 0 270)
			(size 0.45 0.45)
			(layers "F.Cu" "F.Mask" "F.Paste")
			(net "+3.3V")
		)
	)
	(footprint "Vault:FP-CL180-IPC_C"
		(layer "F.Cu")
		(at 213.3261 115.4162 180)
		(property "Reference" "C7"
			(at 3 0.393345 180)
			(unlocked yes)
			(layer "F.SilkS")
			(effects
				(font
					(size 0.762 0.762)
					(thickness 0.2286)
				)
				(justify left bottom)
			)
		)
		(property "Value" "DNI_1nF_50V_0402"
			(at 11.1911 -12.037845 0)
			(unlocked yes)
			(layer "F.SilkS")
			(hide yes)
			(effects
				(font
					(size 0.762 0.762)
					(thickness 0.2286)
				)
				(justify left bottom)
			)
		)
		(sheetname "POWER")
		(sheetfile "POWER.kicad_sch")
		(duplicate_pad_numbers_are_jumpers no)
		(fp_line
			(start 0.63624 0.675)
			(end -0.63624 0.675)
			(stroke
				(width 0.2)
				(type solid)
			)
			(layer "F.SilkS")
		)
		(fp_line
			(start 0.63624 -0.675)
			(end -0.63624 -0.675)
			(stroke
				(width 0.2)
				(type solid)
			)
			(layer "F.SilkS")
		)
		(fp_line
			(start 0.73624 0.375)
			(end -0.73624 0.375)
			(stroke
				(width 0.2)
				(type solid)
			)
			(layer "F.CrtYd")
		)
		(fp_line
			(start 0.73624 -0.375)
			(end 0.73624 0.375)
			(stroke
				(width 0.2)
				(type solid)
			)
			(layer "F.CrtYd")
		)
		(fp_line
			(start 0.73624 -0.375)
			(end -0.73624 -0.375)
			(stroke
				(width 0.2)
				(type solid)
			)
			(layer "F.CrtYd")
		)
		(fp_line
			(start -0.73624 -0.375)
			(end -0.73624 0.375)
			(stroke
				(width 0.2)
				(type solid)
			)
			(layer "F.CrtYd")
		)
		(fp_line
			(start 0.73624 0.375)
			(end -0.73624 0.375)
			(stroke
				(width 0.2)
				(type solid)
			)
			(layer "F.Fab")
		)
		(fp_line
			(start 0.73624 -0.375)
			(end 0.73624 0.375)
			(stroke
				(width 0.2)
				(type solid)
			)
			(layer "F.Fab")
		)
		(fp_line
			(start 0.73624 -0.375)
			(end -0.73624 -0.375)
			(stroke
				(width 0.2)
				(type solid)
			)
			(layer "F.Fab")
		)
		(fp_line
			(start 0.5 0)
			(end -0.5 0)
			(stroke
				(width 0.1)
				(type solid)
			)
			(layer "F.Fab")
		)
		(fp_line
			(start 0.5 0)
			(end -0.5 0)
			(stroke
				(width 0.1)
				(type solid)
			)
			(layer "F.Fab")
		)
		(fp_line
			(start 0 -0.5)
			(end 0 0.5)
			(stroke
				(width 0.1)
				(type solid)
			)
			(layer "F.Fab")
		)
		(fp_line
			(start 0 -0.5)
			(end 0 0.5)
			(stroke
				(width 0.1)
				(type solid)
			)
			(layer "F.Fab")
		)
		(fp_line
			(start -0.73624 -0.375)
			(end -0.73624 0.375)
			(stroke
				(width 0.2)
				(type solid)
			)
			(layer "F.Fab")
		)
		(fp_text user "${REFERENCE}"
			(at 0.00001 0.28425 180)
			(unlocked yes)
			(layer "F.Fab")
			(effects
				(font
					(face "Arial")
					(size 0.63 0.63)
					(thickness 0.1)
				)
				(justify left bottom)
			)
		)
		(pad "1" smd rect
			(at -0.37856 0 180)
			(size 0.51535 0.47247)
			(layers "F.Cu" "F.Mask" "F.Paste")
			(net "NetC7_1")
			(solder_mask_margin 0)
			(solder_paste_margin 0)
		)
		(pad "2" smd rect
			(at 0.37857 0 180)
			(size 0.51535 0.47247)
			(layers "F.Cu" "F.Mask" "F.Paste")
			(net "GND")
			(solder_mask_margin 0)
			(solder_paste_margin 0)
		)
	)
	(footprint "Vault:CAPC1608X87X45ML20T05"
		(layer "F.Cu")
		(at 130.8761 83.5786)
		(property "Reference" "C23"
			(at 1.8786 -2.335469 0)
			(unlocked yes)
			(layer "F.SilkS")
			(effects
				(font
					(size 0.762 0.762)
					(thickness 0.2286)
				)
			)
		)
		(property "Value" "0.1uF"
			(at 2.069035 2.630671 0)
			(unlocked yes)
			(layer "F.SilkS")
			(hide yes)
			(effects
				(font
					(size 0.762 0.762)
					(thickness 0.2286)
				)
			)
		)
		(sheetname "MAC")
		(sheetfile "MAC.kicad_sch")
		(duplicate_pad_numbers_are_jumpers no)
		(pad "1" smd rect
			(at -0.7 0 90)
			(size 1.1 1.05)
			(layers "F.Cu" "F.Mask" "F.Paste")
			(net "GND")
		)
		(pad "2" smd rect
			(at 0.7 0 90)
			(size 1.1 1.05)
			(layers "F.Cu" "F.Mask" "F.Paste")
			(net "+3.3V")
		)
	)
)
